#ISCELL
  mstr_misc dns *
  *
#ISCELL
  pure_quanta quanta_title_block_c *
  *
#ISCELL
  pure_quanta_power cad_note *
  *
#CELL
  pure_quanta q_res *
  page388_i10
#CELL
  pure_quanta q_capp *
  page388_i100
#CELL
  pure_quanta q_cap *
  page388_i101
#CELL
  pure_quanta q_capp *
  page388_i102
#CELL
  pure_quanta q_cap *
  page388_i103
#CELL
  pure_quanta q_cap *
  page388_i104
#CELL
  pure_quanta q_cap *
  page388_i105
#CELL
  pure_quanta q_cap *
  page388_i106
#CELL
  pure_quanta q_res *
  page388_i11
#CELL
  pure_quanta q_inductor *
  page388_i12
#CELL
  pure_quanta q_cap *
  page388_i13
#CELL
  pure_quanta q_cap *
  page388_i14
#ISCELL
  pure_quanta_power p1v0 *
  page388_i15
#CELL
  pure_quanta q_cap *
  page388_i16
#CELL
  pure_quanta q_cap *
  page388_i17
#CELL
  pure_quanta q_cap *
  page388_i18
#CELL
  pure_quanta q_cap *
  page388_i19
#ISCELL
  pure_quanta_power universal_gnd *
  page388_i20
#ISCELL
  pure_quanta_power universal_gnd *
  page388_i21
#CELL
  pure_quanta q_cap *
  page388_i22
#CELL
  pure_quanta q_cap *
  page388_i23
#CELL
  pure_quanta q_cap *
  page388_i24
#CELL
  pure_quanta q_cap *
  page388_i25
#CELL
  pure_quanta q_cap *
  page388_i26
#CELL
  pure_quanta q_cap *
  page388_i27
#CELL
  pure_quanta q_cap *
  page388_i28
#CELL
  pure_quanta q_cap *
  page388_i29
#ISCELL
  pure_quanta_power p1v0 *
  page388_i3
#CELL
  pure_quanta q_inductor *
  page388_i30
#ISCELL
  pure_quanta_power vcc_core *
  page388_i31
#CELL
  pure_quanta q_cap *
  page388_i32
#ISCELL
  pure_quanta_power vcc_core *
  page388_i33
#ISCELL
  pure_quanta_power universal_gnd *
  page388_i35
#CELL
  pure_quanta q_cap *
  page388_i36
#CELL
  pure_quanta q_cap *
  page388_i38
#CELL
  pure_quanta q_cap *
  page388_i39
#CELL
  pure_quanta q_res *
  page388_i4
#CELL
  pure_quanta q_cap *
  page388_i40
#CELL
  pure_quanta q_cap *
  page388_i41
#CELL
  pure_quanta q_cap *
  page388_i42
#CELL
  pure_quanta q_cap *
  page388_i43
#CELL
  pure_quanta q_cap *
  page388_i44
#CELL
  pure_quanta q_cap *
  page388_i45
#CELL
  pure_quanta q_cap *
  page388_i46
#CELL
  pure_quanta q_cap *
  page388_i48
#CELL
  pure_quanta q_cap *
  page388_i49
#CELL
  pure_quanta q_res *
  page388_i5
#CELL
  pure_quanta q_cap *
  page388_i50
#CELL
  pure_quanta q_cap *
  page388_i51
#CELL
  pure_quanta q_cap *
  page388_i52
#CELL
  pure_quanta q_cap *
  page388_i53
#CELL
  pure_quanta q_cap *
  page388_i54
#CELL
  pure_quanta q_cap *
  page388_i55
#CELL
  pure_quanta q_cap *
  page388_i56
#CELL
  pure_quanta q_cap *
  page388_i57
#CELL
  pure_quanta q_cap *
  page388_i58
#CELL
  pure_quanta q_cap *
  page388_i59
#ISCELL
  pure_quanta_power p1v0 *
  page388_i6
#CELL
  pure_quanta q_cap *
  page388_i60
#ISCELL
  pure_quanta_power universal_gnd *
  page388_i61
#CELL
  pure_quanta q_cap *
  page388_i62
#ISCELL
  pure_quanta_power universal_gnd *
  page388_i63
#CELL
  pure_quanta q_cap *
  page388_i65
#CELL
  pure_quanta q_cap *
  page388_i66
#CELL
  pure_quanta q_cap *
  page388_i67
#ISCELL
  pure_quanta_power vcc_core *
  page388_i68
#CELL
  pure_quanta q_cap *
  page388_i69
#ISCELL
  pure_quanta_power universal_gnd *
  page388_i7
#CELL
  pure_quanta q_cap *
  page388_i70
#CELL
  pure_quanta q_cap *
  page388_i71
#CELL
  pure_quanta q_cap *
  page388_i72
#CELL
  pure_quanta q_cap *
  page388_i73
#CELL
  pure_quanta q_cap *
  page388_i74
#CELL
  pure_quanta q_cap *
  page388_i75
#CELL
  pure_quanta q_cap *
  page388_i76
#CELL
  pure_quanta q_cap *
  page388_i77
#CELL
  pure_quanta q_cap *
  page388_i78
#CELL
  pure_quanta q_cap *
  page388_i79
#CELL
  pure_quanta q_cap *
  page388_i8
#CELL
  pure_quanta q_cap *
  page388_i80
#CELL
  pure_quanta q_cap *
  page388_i81
#CELL
  pure_quanta q_cap *
  page388_i82
#CELL
  pure_quanta q_cap *
  page388_i83
#CELL
  pure_quanta q_cap *
  page388_i84
#CELL
  pure_quanta q_cap *
  page388_i85
#ISCELL
  pure_quanta_power universal_gnd *
  page388_i86
#CELL
  pure_quanta q_cap *
  page388_i87
#CELL
  pure_quanta q_inductor *
  page388_i88
#CELL
  pure_quanta q_res *
  page388_i89
#CELL
  pure_quanta q_cap *
  page388_i9
#CELL
  pure_quanta q_cap *
  page388_i90
#CELL
  pure_quanta q_cap *
  page388_i91
#CELL
  pure_quanta q_cap *
  page388_i93
#CELL
  pure_quanta q_cap *
  page388_i94
#CELL
  pure_quanta q_cap *
  page388_i95
#CELL
  pure_quanta q_cap *
  page388_i96
#CELL
  pure_quanta q_capp *
  page388_i97
#CELL
  pure_quanta q_capp *
  page388_i98
#CELL
  pure_quanta q_capp *
  page388_i99
